# SCM (Grand Teton) — schematic netlist excerpt (pin names and nets, part order shuffled) for the footprints in the layout excerpt that follows; sources: Cadence DE-HDL packaged netlist, KiCad conversion of 12092022_DA0F0TMDCD0_F0T_Management_Board_D_brd_V3_OCP.brd

J12  PICOPROBE_BXA  DELTA-L 4.0 EMPTY  pkg TRIANG_LAUNCH_3PXB  page 58
  \1_p\  = 85_5INCH_TOP_DP
  \2_n\  = 85_5INCH_TOP_DN
  \3_g\  = GND_P1

(kicad_pcb
	(version 20260206)
	(generator "pcbnew")
	(generator_version "10.0")
	(general
		(thickness 1.6)
		(legacy_teardrops no)
	)
	(paper "A4")
	(title_block
		(title "12092022_DA0F0TMDCD0_F0T_Management_Board_D_brd_V3_OCP.brd")
		(comment 1 "Grand Teton / footprints 189-189 of 1440")
	)
	(layers
		(0 "F.Cu" signal "TOP")
		(4 "In1.Cu" signal "GND")
		(6 "In2.Cu" signal "IN1")
		(8 "In3.Cu" signal "GND1")
		(10 "In4.Cu" signal "IN2")
		(12 "In5.Cu" signal "VCC")
		(14 "In6.Cu" signal "VCC1")
		(16 "In7.Cu" signal "IN3")
		(18 "In8.Cu" signal "GND2")
		(20 "In9.Cu" signal "IN4")
		(22 "In10.Cu" signal "GND3")
		(2 "B.Cu" signal "BOTTOM")
		(9 "F.Adhes" user "F.Adhesive")
		(11 "B.Adhes" user "B.Adhesive")
		(13 "F.Paste" user "Package Geometry/Pastemask Top")
		(15 "B.Paste" user "Package Geometry/Pastemask Bottom")
		(5 "F.SilkS" user "Ref Des/Silkscreen Top")
		(7 "B.SilkS" user "Ref Des/Silkscreen Bottom")
		(1 "F.Mask" user "Board Geometry/Soldermask Top")
		(3 "B.Mask" user "Board Geometry/Soldermask Bottom")
		(17 "Dwgs.User" user "User.Drawings")
		(19 "Cmts.User" user "User.Comments")
		(21 "Eco1.User" user "User.Eco1")
		(23 "Eco2.User" user "User.Eco2")
		(25 "Edge.Cuts" user "Board Geometry/Outline")
		(27 "Margin" user)
		(31 "F.CrtYd" user "Package Geometry/Place Bound Top")
		(29 "B.CrtYd" user "Package Geometry/Place Bound Bottom")
		(35 "F.Fab" user "Ref Des/Assembly Top")
		(33 "B.Fab" user "Ref Des/Assembly Bottom")
	)
	(footprint ""
		(layer "F.Cu")
		(at 101.2825 -104.76484 -90)
		(property "Reference" "J12"
			(at -3.94716 -1.48717 90)
			(unlocked yes)
			(layer "F.SilkS")
			(effects
				(font
					(size 0.7874 0.5842)
					(thickness 0.1524)
				)
				(justify left)
			)
		)
		(property "Value" ""
			(at 0 0 270)
			(layer "F.Fab")
			(effects
				(font
					(size 1.27 1.27)
				)
			)
		)
		(duplicate_pad_numbers_are_jumpers no)
		(fp_line
			(start -1.2192 2.1082)
			(end -1.2192 -2.1082)
			(stroke
				(width 0.1524)
				(type default)
			)
			(layer "F.SilkS")
		)
		(fp_line
			(start 1.2192 2.1082)
			(end -1.2192 2.1082)
			(stroke
				(width 0.1524)
				(type default)
			)
			(layer "F.SilkS")
		)
		(fp_line
			(start 1.2192 0.466598)
			(end 1.2192 2.1082)
			(stroke
				(width 0.1524)
				(type default)
			)
			(layer "F.SilkS")
		)
		(fp_line
			(start -1.2192 -2.1082)
			(end 1.2192 -2.1082)
			(stroke
				(width 0.1524)
				(type default)
			)
			(layer "F.SilkS")
		)
		(fp_line
			(start 1.2192 -2.1082)
			(end 1.2192 -0.454406)
			(stroke
				(width 0.1524)
				(type default)
			)
			(layer "F.SilkS")
		)
		(pad "" np_thru_hole circle
			(at -2.8829 -1.27 180)
			(size 1.0414 1.0414)
			(drill 1.0414)
			(layers "*.Cu" "*.Mask")
			(clearance 0.381)
			(thermal_gap 0.381)
		)
		(pad "" np_thru_hole circle
			(at -2.8829 1.27 180)
			(size 1.0414 1.0414)
			(drill 1.0414)
			(layers "*.Cu" "*.Mask")
			(clearance 0.381)
			(thermal_gap 0.381)
		)
		(pad "" np_thru_hole circle
			(at 3.4671 -1.27 180)
			(size 1.0414 1.0414)
			(drill 1.0414)
			(layers "*.Cu" "*.Mask")
			(clearance 0.381)
			(thermal_gap 0.381)
		)
		(pad "" np_thru_hole circle
			(at 3.4671 1.27 180)
			(size 1.0414 1.0414)
			(drill 1.0414)
			(layers "*.Cu" "*.Mask")
			(clearance 0.381)
			(thermal_gap 0.381)
		)
		(pad "1" smd rect
			(at 0.8255 -0.249936 180)
			(size 0.3048 0.508)
			(layers "F.Cu" "F.Mask" "F.Paste")
			(net "85_5INCH_TOP_DP")
		)
		(pad "2" smd rect
			(at 0.8255 0.249936 180)
			(size 0.3048 0.508)
			(layers "F.Cu" "F.Mask" "F.Paste")
			(net "85_5INCH_TOP_DN")
		)
		(pad "3" smd circle
			(at 0 0 270)
			(size 0 0)
			(layers "F.Cu" "F.Mask" "F.Paste")
			(net "GND_P1")
		)
		(zone
			(layer "F.Cu")
			(hatch none 0.5)
			(connect_pads
				(clearance 0)
			)
			(min_thickness 0.25)
			(keepout
				(tracks not_allowed)
				(vias allowed)
				(pads allowed)
				(copperpour not_allowed)
				(footprints allowed)
			)
			(placement
				(enabled no)
				(sheetname "")
			)
			(fill
				(thermal_gap 0.5)
				(thermal_bridge_width 0.5)
				(island_removal_mode 0)
			)
			(polygon
				(pts
					(xy 101.83114 -103.64724) (xy 101.735636 -103.64724) (xy 101.735636 -104.24414) (xy 101.329236 -104.24414)
					(xy 101.329236 -103.64724) (xy 101.235764 -103.64724) (xy 101.235764 -104.24414) (xy 100.829364 -104.24414)
					(xy 100.829364 -103.64724) (xy 100.73386 -103.64724) (xy 100.73386 -104.34574) (xy 101.83114 -104.34574)
				)
			)
		)
		(zone
			(layers "F.Cu" "B.Cu" "In1.Cu" "In2.Cu" "In3.Cu" "In4.Cu" "In5.Cu" "In6.Cu"
				"In7.Cu" "In8.Cu" "In9.Cu" "In10.Cu"
			)
			(hatch none 0.5)
			(connect_pads
				(clearance 0)
			)
			(min_thickness 0.25)
			(keepout
				(tracks not_allowed)
				(vias allowed)
				(pads allowed)
				(copperpour not_allowed)
				(footprints allowed)
			)
			(placement
				(enabled no)
				(sheetname "")
			)
			(fill
				(thermal_gap 0.5)
				(thermal_bridge_width 0.5)
				(island_removal_mode 0)
			)
			(polygon
				(pts
					(arc
						(start 100.9396 -107.64774)
						(mid 99.0854 -107.64774)
						(end 100.9396 -107.64774)
					)
				)
			)
		)
		(zone
			(layers "F.Cu" "B.Cu" "In1.Cu" "In2.Cu" "In3.Cu" "In4.Cu" "In5.Cu" "In6.Cu"
				"In7.Cu" "In8.Cu" "In9.Cu" "In10.Cu"
			)
			(hatch none 0.5)
			(connect_pads
				(clearance 0)
			)
			(min_thickness 0.25)
			(keepout
				(tracks not_allowed)
				(vias allowed)
				(pads allowed)
				(copperpour not_allowed)
				(footprints allowed)
			)
			(placement
				(enabled no)
				(sheetname "")
			)
			(fill
				(thermal_gap 0.5)
				(thermal_bridge_width 0.5)
				(island_removal_mode 0)
			)
			(polygon
				(pts
					(arc
						(start 100.9396 -101.29774)
						(mid 99.0854 -101.29774)
						(end 100.9396 -101.29774)
					)
				)
			)
		)
		(zone
			(layers "F.Cu" "B.Cu" "In1.Cu" "In2.Cu" "In3.Cu" "In4.Cu" "In5.Cu" "In6.Cu"
				"In7.Cu" "In8.Cu" "In9.Cu" "In10.Cu"
			)
			(hatch none 0.5)
			(connect_pads
				(clearance 0)
			)
			(min_thickness 0.25)
			(keepout
				(tracks not_allowed)
				(vias allowed)
				(pads allowed)
				(copperpour not_allowed)
				(footprints allowed)
			)
			(placement
				(enabled no)
				(sheetname "")
			)
			(fill
				(thermal_gap 0.5)
				(thermal_bridge_width 0.5)
				(island_removal_mode 0)
			)
			(polygon
				(pts
					(arc
						(start 103.4796 -107.64774)
						(mid 101.6254 -107.64774)
						(end 103.4796 -107.64774)
					)
				)
			)
		)
		(zone
			(layers "F.Cu" "B.Cu" "In1.Cu" "In2.Cu" "In3.Cu" "In4.Cu" "In5.Cu" "In6.Cu"
				"In7.Cu" "In8.Cu" "In9.Cu" "In10.Cu"
			)
			(hatch none 0.5)
			(connect_pads
				(clearance 0)
			)
			(min_thickness 0.25)
			(keepout
				(tracks not_allowed)
				(vias allowed)
				(pads allowed)
				(copperpour not_allowed)
				(footprints allowed)
			)
			(placement
				(enabled no)
				(sheetname "")
			)
			(fill
				(thermal_gap 0.5)
				(thermal_bridge_width 0.5)
				(island_removal_mode 0)
			)
			(polygon
				(pts
					(arc
						(start 103.4796 -101.29774)
						(mid 101.6254 -101.29774)
						(end 103.4796 -101.29774)
					)
				)
			)
		)
	)
)
